# S9S_MB_2U (Grand Teton) — schematic netlist excerpt (pin names and nets, part order shuffled) for the footprints in the layout excerpt that follows; sources: Cadence DE-HDL packaged netlist, KiCad conversion of 03242023_DA0F0TMBIJ0_F0T_Motherboard_J_brd_V01_OCP.brd

R2591  Q_RES  0 5% CHIP  pkg 0402LF  page 266 : A = FM_PVCCIN_CPU0_EN ; B = PVCCIN_CPU0_EN_R
PR149  Q_RES  0 5% CHIP  pkg 0402LF  page 268 : A = PVCCIN_CPU0_VOS3 ; B = PVCCIN_CPU0

(kicad_pcb
	(version 20260206)
	(generator "pcbnew")
	(generator_version "10.0")
	(general
		(thickness 1.6)
		(legacy_teardrops no)
	)
	(paper "A4")
	(title_block
		(title "03242023_DA0F0TMBIJ0_F0T_Motherboard_J_brd_V01_OCP.brd")
		(comment 1 "Grand Teton / footprints 4290-4291 of 6105")
	)
	(layers
		(0 "F.Cu" signal "TOP")
		(4 "In1.Cu" signal "GND")
		(6 "In2.Cu" signal "IN1")
		(8 "In3.Cu" signal "GND1")
		(10 "In4.Cu" signal "IN2")
		(12 "In5.Cu" signal "GND2")
		(14 "In6.Cu" signal "IN3")
		(16 "In7.Cu" signal "GND3")
		(18 "In8.Cu" signal "VCC")
		(20 "In9.Cu" signal "VCC1")
		(22 "In10.Cu" signal "GND4")
		(24 "In11.Cu" signal "IN4")
		(26 "In12.Cu" signal "GND5")
		(28 "In13.Cu" signal "IN5")
		(30 "In14.Cu" signal "GND6")
		(32 "In15.Cu" signal "IN6")
		(34 "In16.Cu" signal "GND7")
		(2 "B.Cu" signal "BOTTOM")
		(9 "F.Adhes" user "F.Adhesive")
		(11 "B.Adhes" user "B.Adhesive")
		(13 "F.Paste" user "Package Geometry/Pastemask Top")
		(15 "B.Paste" user "Package Geometry/Pastemask Bottom")
		(5 "F.SilkS" user "Ref Des/Silkscreen Top")
		(7 "B.SilkS" user "Ref Des/Silkscreen Bottom")
		(1 "F.Mask" user "Board Geometry/Soldermask Top")
		(3 "B.Mask" user "Board Geometry/Soldermask Bottom")
		(17 "Dwgs.User" user "User.Drawings")
		(19 "Cmts.User" user "User.Comments")
		(21 "Eco1.User" user "User.Eco1")
		(23 "Eco2.User" user "User.Eco2")
		(25 "Edge.Cuts" user "Board Geometry/Outline")
		(27 "Margin" user)
		(31 "F.CrtYd" user "Package Geometry/Place Bound Top")
		(29 "B.CrtYd" user "Package Geometry/Place Bound Bottom")
		(35 "F.Fab" user "Ref Des/Assembly Top")
		(33 "B.Fab" user "Ref Des/Assembly Bottom")
	)
	(footprint ""
		(layer "B.Cu")
		(at 358.328214 -337.860386)
		(property "Reference" "PR149"
			(at 0 0 0)
			(layer "B.SilkS")
			(hide yes)
			(effects
				(font
					(size 1.27 1.27)
				)
				(justify mirror)
			)
		)
		(property "Value" ""
			(at 0 0 0)
			(layer "B.Fab")
			(effects
				(font
					(size 1.27 1.27)
				)
				(justify mirror)
			)
		)
		(duplicate_pad_numbers_are_jumpers no)
		(fp_line
			(start -0.7874 -0.4064)
			(end -0.7874 0.4064)
			(stroke
				(width 0.1524)
				(type default)
			)
			(layer "B.SilkS")
		)
		(fp_line
			(start -0.7874 0.4064)
			(end 0.7874 0.4064)
			(stroke
				(width 0.1524)
				(type default)
			)
			(layer "B.SilkS")
		)
		(fp_line
			(start 0.7874 -0.4064)
			(end -0.7874 -0.4064)
			(stroke
				(width 0.1524)
				(type default)
			)
			(layer "B.SilkS")
		)
		(fp_line
			(start 0.7874 0.4064)
			(end 0.7874 -0.4064)
			(stroke
				(width 0.1524)
				(type default)
			)
			(layer "B.SilkS")
		)
		(fp_line
			(start -0.67945 -0.3048)
			(end -0.67945 0.3048)
			(stroke
				(width 0.1)
				(type default)
			)
			(layer "B.Fab")
		)
		(fp_line
			(start -0.67945 0.3048)
			(end -0.120396 0.3048)
			(stroke
				(width 0.1)
				(type default)
			)
			(layer "B.Fab")
		)
		(fp_line
			(start -0.12065 -0.3048)
			(end -0.67945 -0.3048)
			(stroke
				(width 0.1)
				(type default)
			)
			(layer "B.Fab")
		)
		(fp_line
			(start -0.12065 -0.2794)
			(end -0.12065 -0.3048)
			(stroke
				(width 0.1)
				(type default)
			)
			(layer "B.Fab")
		)
		(fp_line
			(start -0.120396 0.2794)
			(end 0.12065 0.2794)
			(stroke
				(width 0.1)
				(type default)
			)
			(layer "B.Fab")
		)
		(fp_line
			(start -0.120396 0.3048)
			(end -0.120396 0.2794)
			(stroke
				(width 0.1)
				(type default)
			)
			(layer "B.Fab")
		)
		(fp_line
			(start 0.12065 -0.305054)
			(end 0.12065 -0.2794)
			(stroke
				(width 0.1)
				(type default)
			)
			(layer "B.Fab")
		)
		(fp_line
			(start 0.12065 -0.2794)
			(end -0.12065 -0.2794)
			(stroke
				(width 0.1)
				(type default)
			)
			(layer "B.Fab")
		)
		(fp_line
			(start 0.12065 0.2794)
			(end 0.12065 0.3048)
			(stroke
				(width 0.1)
				(type default)
			)
			(layer "B.Fab")
		)
		(fp_line
			(start 0.12065 0.3048)
			(end 0.67945 0.3048)
			(stroke
				(width 0.1)
				(type default)
			)
			(layer "B.Fab")
		)
		(fp_line
			(start 0.67945 -0.305054)
			(end 0.12065 -0.305054)
			(stroke
				(width 0.1)
				(type default)
			)
			(layer "B.Fab")
		)
		(fp_line
			(start 0.67945 0.3048)
			(end 0.67945 -0.305054)
			(stroke
				(width 0.1)
				(type default)
			)
			(layer "B.Fab")
		)
		(pad "1" smd circle
			(at 0.40005 0 180)
			(size 0 0)
			(layers "B.Cu" "B.Mask" "B.Paste")
			(net "PVCCIN_CPU0_VOS3")
		)
		(pad "2" smd circle
			(at -0.40005 0 180)
			(size 0 0)
			(layers "B.Cu" "B.Mask" "B.Paste")
			(net "PVCCIN_CPU0")
		)
	)
	(footprint ""
		(layer "B.Cu")
		(at 351.26803 -359.995216 180)
		(property "Reference" "R2591"
			(at 0 0 0)
			(layer "B.SilkS")
			(hide yes)
			(effects
				(font
					(size 1.27 1.27)
				)
				(justify mirror)
			)
		)
		(property "Value" ""
			(at 0 0 0)
			(layer "B.Fab")
			(effects
				(font
					(size 1.27 1.27)
				)
				(justify mirror)
			)
		)
		(duplicate_pad_numbers_are_jumpers no)
		(fp_line
			(start 0.7874 0.4064)
			(end 0.7874 -0.4064)
			(stroke
				(width 0.1524)
				(type default)
			)
			(layer "B.SilkS")
		)
		(fp_line
			(start 0.7874 -0.4064)
			(end -0.7874 -0.4064)
			(stroke
				(width 0.1524)
				(type default)
			)
			(layer "B.SilkS")
		)
		(fp_line
			(start -0.7874 0.4064)
			(end 0.7874 0.4064)
			(stroke
				(width 0.1524)
				(type default)
			)
			(layer "B.SilkS")
		)
		(fp_line
			(start -0.7874 -0.4064)
			(end -0.7874 0.4064)
			(stroke
				(width 0.1524)
				(type default)
			)
			(layer "B.SilkS")
		)
		(fp_line
			(start 0.67945 0.3048)
			(end 0.67945 -0.305054)
			(stroke
				(width 0.1)
				(type default)
			)
			(layer "B.Fab")
		)
		(fp_line
			(start 0.67945 -0.305054)
			(end 0.12065 -0.305054)
			(stroke
				(width 0.1)
				(type default)
			)
			(layer "B.Fab")
		)
		(fp_line
			(start 0.12065 0.3048)
			(end 0.67945 0.3048)
			(stroke
				(width 0.1)
				(type default)
			)
			(layer "B.Fab")
		)
		(fp_line
			(start 0.12065 0.2794)
			(end 0.12065 0.3048)
			(stroke
				(width 0.1)
				(type default)
			)
			(layer "B.Fab")
		)
		(fp_line
			(start 0.12065 -0.2794)
			(end -0.12065 -0.2794)
			(stroke
				(width 0.1)
				(type default)
			)
			(layer "B.Fab")
		)
		(fp_line
			(start 0.12065 -0.305054)
			(end 0.12065 -0.2794)
			(stroke
				(width 0.1)
				(type default)
			)
			(layer "B.Fab")
		)
		(fp_line
			(start -0.120396 0.3048)
			(end -0.120396 0.2794)
			(stroke
				(width 0.1)
				(type default)
			)
			(layer "B.Fab")
		)
		(fp_line
			(start -0.120396 0.2794)
			(end 0.12065 0.2794)
			(stroke
				(width 0.1)
				(type default)
			)
			(layer "B.Fab")
		)
		(fp_line
			(start -0.12065 -0.2794)
			(end -0.12065 -0.3048)
			(stroke
				(width 0.1)
				(type default)
			)
			(layer "B.Fab")
		)
		(fp_line
			(start -0.12065 -0.3048)
			(end -0.67945 -0.3048)
			(stroke
				(width 0.1)
				(type default)
			)
			(layer "B.Fab")
		)
		(fp_line
			(start -0.67945 0.3048)
			(end -0.120396 0.3048)
			(stroke
				(width 0.1)
				(type default)
			)
			(layer "B.Fab")
		)
		(fp_line
			(start -0.67945 -0.3048)
			(end -0.67945 0.3048)
			(stroke
				(width 0.1)
				(type default)
			)
			(layer "B.Fab")
		)
		(pad "1" smd circle
			(at 0.40005 0)
			(size 0 0)
			(layers "B.Cu" "B.Mask" "B.Paste")
			(net "FM_PVCCIN_CPU0_EN")
		)
		(pad "2" smd circle
			(at -0.40005 0)
			(size 0 0)
			(layers "B.Cu" "B.Mask" "B.Paste")
			(net "PVCCIN_CPU0_EN_R")
		)
	)
)
